G04 ================== begin FILE IDENTIFICATION RECORD ==================*
G04 Layout Name:  16368-sb.brd*
G04 Film Name:    L3*
G04 File Format:  Gerber RS274X*
G04 File Origin:  Cadence Allegro 16.5-S056*
G04 Origin Date:  Tue Feb 07 09:07:43 2017*
G04 *
G04 Layer:  VIA CLASS/L3*
G04 Layer:  PIN/L3*
G04 Layer:  ETCH/L3*
G04 Layer:  DRAWING FORMAT/LAYER_PCB_STORY*
G04 Layer:  DRAWING FORMAT/LAYER_L3*
G04 *
G04 Offset:    (0.00 0.00)*
G04 Mirror:    No*
G04 Mode:      Positive*
G04 Rotation:  0*
G04 FullContactRelief:  No*
G04 UndefLineWidth:     6.00*
G04 ================== end FILE IDENTIFICATION RECORD ====================*
%FSLAX35Y35*MOIN*%
%IR0*IPPOS*OFA0.00000B0.00000*MIA0B0*SFA1.00000B1.00000*%
%ADD12C,.02*%
%ADD11C,.042*%
%ADD10C,.034*%
%ADD13C,.005*%
%ADD14C,.006*%
%ADD19C,.05004*%
%ADD17C,.04404*%
%ADD18C,.04604*%
%ADD16C,.06404*%
%ADD20C,.06604*%
%ADD15C,.11004*%
G75*
%LPD*%
G75*
G36*
G01X3937Y3001D02*
G02X3001Y3937I0J936D01*
G01Y57874D01*
G02X3937Y58810I936J0D01*
G01X24190D01*
X25500Y57500D01*
Y54500D01*
X20000Y49000D01*
Y30169D01*
G02X19529Y29775I-400J0D01*
G03X14605Y29453I-1813J-10090D01*
G02X14100Y29947I-121J381D01*
G03X10638Y27949I-2783J823D01*
G02X10814Y27264I-93J-389D01*
G03X10138Y26588I6903J-7579D01*
G02X9453Y26764I-296J269D01*
G03X7455Y23302I-2821J-679D01*
G02X7949Y22797I113J-384D01*
G03Y16573I9768J-3112D01*
G02X7455Y16068I-381J-121D01*
G03X9453Y12606I-823J-2783D01*
G02X10138Y12782I389J-93D01*
G03X10814Y12106I7579J6903D01*
G02X10638Y11421I-269J-296D01*
G03X14100Y9423I679J-2821D01*
G02X14605Y9917I384J113D01*
G03X20829I3112J9768D01*
G02X21334Y9423I121J-381D01*
G03X24796Y11421I2783J-823D01*
G02X24620Y12106I93J389D01*
G03X25296Y12782I-6903J7579D01*
G02X25981Y12606I296J-269D01*
G03X27979Y16068I2821J679D01*
G02X27485Y16573I-113J384D01*
G03X27907Y20802I-9768J3110D01*
G01X27897Y20897D01*
X33500Y26500D01*
X41500D01*
X50500Y17500D01*
X64500D01*
X66000Y16000D01*
Y13000D01*
X67500Y11500D01*
X69500D01*
X71000Y13000D01*
Y15000D01*
X76500Y20500D01*
Y23000D01*
X75500Y24000D01*
X73000D01*
X71000Y22000D01*
X68500D01*
X67500Y23000D01*
Y24347D01*
G03Y24527I-2200J90D01*
G01Y26500D01*
X69000Y28000D01*
X80500D01*
X82000Y26500D01*
Y20000D01*
X84500Y17500D01*
X99000D01*
X108000Y8500D01*
X113000D01*
X117800Y3700D01*
X133700D01*
X137000Y7000D01*
Y10000D01*
X136000Y11000D01*
Y16500D01*
X134500Y18000D01*
X129000D01*
X124500Y22500D01*
X111000D01*
X96000Y37500D01*
X79500D01*
X77000Y40000D01*
X63500D01*
X60000Y43500D01*
Y48000D01*
X58500Y49500D01*
X51000D01*
X48000Y52500D01*
X36500D01*
X35500Y53500D01*
Y55205D01*
G03Y55623I-3295J209D01*
G01Y57500D01*
X36810Y58810D01*
X48929D01*
G02X49163Y58086I0J-400D01*
G03X53949Y53739I1940J-2672D01*
G02X54556Y53838I345J-203D01*
G03X54498Y57110I1444J1662D01*
G02X53888Y57188I-273J293D01*
G03X53043Y58086I-2785J-1774D01*
G02X53277Y58810I234J324D01*
G01X173228D01*
G02X174164Y57874I0J-936D01*
G01Y3937D01*
G02X173228Y3001I-936J0D01*
G01X3937D01*
G37*
G36*
G01X53500Y28000D02*
X31000D01*
X25300Y33700D01*
X23300D01*
X21300Y35700D01*
Y48500D01*
X24900Y52100D01*
X29200D01*
X31900Y49400D01*
Y45400D01*
X28100Y41600D01*
X27000D01*
X25600Y40200D01*
Y38400D01*
X27000Y37000D01*
X29000D01*
X30900Y35100D01*
X33500D01*
X35600Y37200D01*
Y42100D01*
X37000Y43500D01*
X58000D01*
X60500Y41000D01*
Y35000D01*
X53500Y28000D01*
G37*
G36*
G01X118500Y5000D02*
X110000Y13500D01*
X105000D01*
X99500Y19000D01*
X85000D01*
X83500Y20500D01*
Y22000D01*
X87000Y25500D01*
Y28000D01*
X85500Y29500D01*
X66500D01*
X56000Y19000D01*
X52500D01*
X51500Y20000D01*
Y24000D01*
X63500Y36000D01*
X74663D01*
G03X77337I1337J1750D01*
G01X95500D01*
X110500Y21000D01*
X124000D01*
X135500Y9500D01*
Y7500D01*
X133000Y5000D01*
X118500D01*
G37*
%LPC*%
G75*
G36*
G01X95142Y49188D02*
G03X95291Y48946I194J-47D01*
G02X92658Y47312I-492J-2146D01*
G03X92509Y47554I-194J47D01*
G02X95142Y49188I492J2146D01*
G37*
G36*
G01X83911Y12706D02*
G03X83695Y12523I-17J-199D01*
G02X81689Y14894I-2195J177D01*
G03X81905Y15077I17J199D01*
G02X83911Y12706I2195J-177D01*
G37*
G36*
G01X156337Y9917D02*
G03X155832Y9423I-121J-381D01*
G02X152370Y11421I-2783J-823D01*
G03X152546Y12106I-93J389D01*
G02X151870Y12782I6903J7579D01*
G03X151185Y12606I-296J-269D01*
G02X149187Y16068I-2821J679D01*
G03X149681Y16573I113J384D01*
G02Y22797I9768J3112D01*
G03X149187Y23302I-381J121D01*
G02X151185Y26764I-823J2783D01*
G03X151870Y26588I389J93D01*
G02X152546Y27264I7579J-6903D01*
G03X152370Y27949I-269J296D01*
G02X155832Y29947I679J2821D01*
G03X156337Y29453I384J-113D01*
G02X162561I3112J-9768D01*
G03X163066Y29947I121J381D01*
G02X166528Y27949I2783J823D01*
G03X166352Y27264I93J-389D01*
G02X167028Y26588I-6903J-7579D01*
G03X167713Y26764I296J269D01*
G02X169711Y23302I2821J-679D01*
G03X169217Y22797I-113J-384D01*
G02Y16573I-9768J-3112D01*
G03X169711Y16068I381J-121D01*
G02X167713Y12606I823J-2783D01*
G03X167028Y12782I-389J-93D01*
G02X166352Y12106I-7579J6903D01*
G03X166528Y11421I269J-296D01*
G02X163066Y9423I-679J-2821D01*
G03X162561Y9917I-384J113D01*
G02X156337I-3112J9768D01*
G37*
G54D19*
X26890Y46949D03*
G54D17*
X95400Y12500D03*
X53437Y13900D03*
X103700Y36400D03*
X87700Y43400D03*
X119500Y33900D03*
X45250Y35850D03*
X39300Y35500D03*
X98000Y25500D03*
G54D18*
X111800Y52264D03*
X96000Y55600D03*
X111700Y39600D03*
X127500Y52264D03*
Y37000D03*
G54D16*
X103642Y43898D03*
X127264D03*
G54D20*
X51103Y38484D03*
G54D15*
X9000Y48000D03*
X164500Y48500D03*
%LPD*%
G75*
G54D10*
X28802Y13285D03*
X24117Y8600D03*
X11317D03*
X6632Y13285D03*
Y26085D03*
X11317Y30770D03*
X170534Y13285D03*
X165849Y8600D03*
X153049D03*
X148364Y13285D03*
Y26085D03*
X153049Y30770D03*
X165849D03*
X170534Y26085D03*
G54D11*
X32205Y55414D03*
X51103D03*
G54D12*
G01X-149983Y-76117D02*
Y-156117D01*
G01D02*
X864117D01*
G01X-153983Y-60117D02*
G02I-12000J0D01*
G01X-159133D02*
G02I-6850J0D01*
G01X-165983Y-76117D02*
Y-44117D01*
G01X-149983Y-60117D02*
X-181983D01*
G01X-149983Y-76117D02*
X864117D01*
G01X-149983Y-111617D02*
X864117D01*
G01X11317Y30770D02*
Y33872D01*
G01X8215Y30770D02*
X11317D01*
G01D02*
X14419D01*
G01X6632Y22983D02*
Y26085D01*
G01D02*
Y29187D01*
G01Y10183D02*
Y13285D01*
G01D02*
Y16387D01*
G01X11317Y5498D02*
Y8600D01*
G01X8215D02*
X11317D01*
G01D02*
X14419D01*
G01X24117Y5498D02*
Y8600D01*
G01X21015D02*
X24117D01*
G01D02*
X27219D01*
G01X28802Y10183D02*
Y13285D01*
G01D02*
Y16387D01*
G01Y13285D02*
X31904D01*
G01X32205Y55414D02*
X36586D01*
G01X76617Y-76117D02*
Y-156117D01*
G01X51103Y51912D02*
Y55414D01*
G01X47601D02*
X51103D01*
G01X170534Y22983D02*
Y26085D01*
G01D02*
Y29187D01*
G01X165849Y30770D02*
Y33872D01*
G01X162747Y30770D02*
X165849D01*
G01D02*
X168951D01*
G01X153049D02*
Y33872D01*
G01X149947Y30770D02*
X153049D01*
G01D02*
X156151D01*
G01X148364Y22983D02*
Y26085D01*
G01D02*
Y29187D01*
G01X145262Y26085D02*
X148364D01*
G01Y10183D02*
Y13285D01*
G01D02*
Y16387D01*
G01X145262Y13285D02*
X148364D01*
G01X153049Y5498D02*
Y8600D01*
G01X149947D02*
X153049D01*
G01D02*
X156151D01*
G01X165849Y5498D02*
Y8600D01*
G01X162747D02*
X165849D01*
G01D02*
X168951D01*
G01X170534Y10183D02*
Y13285D01*
G01D02*
Y16387D01*
G01X214117Y-76117D02*
Y-156117D01*
G01X329117Y-76117D02*
Y-156117D01*
G01X496617Y-76117D02*
Y-156117D01*
G01X666617Y-76117D02*
Y-156117D01*
G01X864117Y-76117D02*
Y-156117D01*
G01X892117Y-60117D02*
G02I-12000J0D01*
G01X886967D02*
G02I-6850J0D01*
G01X880117Y-76117D02*
Y-44117D01*
G01X896117Y-60117D02*
X864117D01*
X28100Y39300D03*
Y55300D03*
X20000Y55000D03*
X15000Y45000D03*
X5000Y38000D03*
Y55000D03*
X30827Y47067D03*
X68750Y24100D03*
X79940Y26850D03*
X70700Y11200D03*
X40100Y21692D03*
X35000Y5000D03*
X41200Y7400D03*
X98200Y16500D03*
X108140Y28132D03*
X54500Y25500D03*
X98700Y21000D03*
X95300D03*
X85100Y21100D03*
X56200Y21000D03*
X52800D03*
X44607Y46831D03*
X39400D03*
X52218Y47067D03*
X49730Y46821D03*
X87900Y53100D03*
X103655Y52264D03*
X61300Y47250D03*
X88940Y39400D03*
X58000Y38500D03*
X74000Y34900D03*
X119400Y29800D03*
X143000Y5000D03*
X137000Y12750D03*
X118300Y19900D03*
X134200Y9000D03*
X131000Y6000D03*
X170000Y45000D03*
X135500D03*
X155000D03*
X165000Y55000D03*
X145000D03*
Y36500D03*
X119403Y52264D03*
G54D13*
G01X52218Y47067D02*
Y45718D01*
X51500Y45000D01*
X33800D01*
X28100Y39300D01*
G01X49730Y46821D02*
Y48270D01*
X47000Y51000D01*
X32400D01*
X28100Y55300D01*
G01X39400Y46831D02*
X44607D01*
G54D14*
G01X-137600Y-128617D02*
Y-146117D01*
X-128866D01*
G01X-113987Y-136784D02*
X-113113Y-135909D01*
X-112458Y-134451D01*
X-112021Y-132408D01*
X-112458Y-130659D01*
X-113331Y-129492D01*
X-114860Y-128617D01*
X-120755D01*
Y-146117D01*
X-113550D01*
X-112021Y-144951D01*
X-111148Y-143200D01*
X-110711Y-141159D01*
X-111148Y-139117D01*
X-112458Y-137367D01*
X-113987Y-136784D01*
X-120755D01*
G01X-93430Y-130076D02*
X-94740Y-129200D01*
X-96268Y-128617D01*
X-98015D01*
X-99980Y-129492D01*
X-101508Y-130950D01*
X-102600Y-132701D01*
X-103473Y-135617D01*
X-103692Y-138242D01*
X-103255Y-140867D01*
X-102600Y-142617D01*
X-101290Y-144367D01*
X-99761Y-145534D01*
X-98233Y-146117D01*
X-96705D01*
X-95176Y-145534D01*
X-93866Y-144659D01*
X-92774Y-143493D01*
G01X-67600Y-128617D02*
Y-146117D01*
X-58866D01*
G01X-41366D02*
X-50100D01*
Y-128617D01*
X-41366D01*
G01X-44860Y-137075D02*
X-50100D01*
G01X-33036Y-146117D02*
Y-128617D01*
X-28670D01*
X-26923Y-129492D01*
X-25613Y-130659D01*
X-24521Y-132408D01*
X-23648Y-134451D01*
X-23430Y-137367D01*
X-23648Y-140284D01*
X-24521Y-142326D01*
X-25613Y-144076D01*
X-26923Y-145242D01*
X-28670Y-146117D01*
X-33036D01*
G01X10260Y-135909D02*
X8732Y-134742D01*
X7422Y-134451D01*
X5675Y-135034D01*
X4365Y-136200D01*
X3492Y-138242D01*
X3273Y-140284D01*
X3492Y-142326D01*
X4365Y-144076D01*
X5675Y-145534D01*
X7422Y-146117D01*
X8950Y-145534D01*
X10260Y-144367D01*
G01X28197Y-146117D02*
Y-134451D01*
G01Y-136492D02*
X27324Y-135326D01*
X26013Y-134742D01*
X24485Y-134451D01*
X22957Y-135034D01*
X21647Y-136200D01*
X20773Y-137950D01*
X20337Y-140284D01*
X20773Y-142617D01*
X21647Y-144367D01*
X22957Y-145534D01*
X24485Y-146117D01*
X26013Y-145825D01*
X27324Y-144951D01*
X28197Y-143784D01*
G01X38710Y-146117D02*
Y-134451D01*
G01Y-136784D02*
X39802Y-135617D01*
X40894Y-134742D01*
X42422Y-134451D01*
X43513Y-134742D01*
X44824Y-135617D01*
G01X63197Y-128617D02*
Y-146117D01*
G01Y-143493D02*
X62324Y-144951D01*
X61013Y-145825D01*
X59485Y-146117D01*
X57739Y-145534D01*
X56429Y-144076D01*
X55555Y-142326D01*
X55337Y-140284D01*
X55555Y-138242D01*
X56429Y-136492D01*
X57739Y-135034D01*
X59485Y-134451D01*
X61013Y-134742D01*
X62105Y-135326D01*
X63197Y-136492D01*
G01X-77660Y-101117D02*
Y-83617D01*
X-71983Y-98200D01*
X-66306Y-83617D01*
Y-101117D01*
G01X-54483D02*
X-55793Y-100825D01*
X-57103Y-99659D01*
X-57977Y-97617D01*
X-58413Y-95284D01*
X-57977Y-92950D01*
X-57103Y-90909D01*
X-55793Y-89742D01*
X-54483Y-89451D01*
X-53173Y-89742D01*
X-51863Y-90909D01*
X-50990Y-92950D01*
X-50771Y-95284D01*
X-50990Y-97617D01*
X-51863Y-99659D01*
X-53173Y-100825D01*
X-54483Y-101117D01*
G01X-33053Y-83617D02*
Y-101117D01*
G01Y-98493D02*
X-33926Y-99951D01*
X-35237Y-100825D01*
X-36765Y-101117D01*
X-38511Y-100534D01*
X-39821Y-99076D01*
X-40695Y-97326D01*
X-40913Y-95284D01*
X-40695Y-93242D01*
X-39821Y-91492D01*
X-38511Y-90034D01*
X-36765Y-89451D01*
X-35237Y-89742D01*
X-34145Y-90326D01*
X-33053Y-91492D01*
G01X-22758Y-93242D02*
X-15771D01*
X-16426Y-91200D01*
X-17518Y-90034D01*
X-19046Y-89451D01*
X-20575Y-89742D01*
X-21885Y-90617D01*
X-22758Y-92659D01*
X-23195Y-94409D01*
Y-96159D01*
X-22758Y-97909D01*
X-21666Y-99659D01*
X-20356Y-100825D01*
X-18828Y-101117D01*
X-17300Y-100534D01*
X-15771Y-98784D01*
G01X-1983Y-101117D02*
Y-83617D01*
G01X110317Y-146117D02*
Y-128617D01*
X107697Y-132117D01*
G01Y-146117D02*
X112937D01*
G01X123669Y-138826D02*
X125197Y-136784D01*
X126507Y-135617D01*
X128254Y-135034D01*
X129782Y-135617D01*
X130874Y-136784D01*
X131747Y-138534D01*
X131965Y-140575D01*
X131747Y-142326D01*
X130874Y-144076D01*
X129563Y-145534D01*
X128035Y-146117D01*
X126289Y-145534D01*
X124760Y-143784D01*
X123887Y-141159D01*
X123669Y-138242D01*
X124105Y-134451D01*
X124760Y-132408D01*
X125852Y-130367D01*
X127380Y-128909D01*
X128909Y-128617D01*
X130437Y-129200D01*
X131529Y-130659D01*
G01X140514Y-142617D02*
X141823Y-144659D01*
X143570Y-145825D01*
X145535Y-146117D01*
X147282Y-145825D01*
X149029Y-144367D01*
X150120Y-142617D01*
X150339Y-140867D01*
X149902Y-138826D01*
X148374Y-137367D01*
X146845Y-136784D01*
X144880D01*
G01X146845D02*
X148155Y-135909D01*
X149247Y-134451D01*
X149684Y-132701D01*
X149247Y-130950D01*
X148155Y-129492D01*
X146190Y-128617D01*
X144225Y-128909D01*
X142260Y-130076D01*
G01X158669Y-138826D02*
X160197Y-136784D01*
X161507Y-135617D01*
X163254Y-135034D01*
X164782Y-135617D01*
X165874Y-136784D01*
X166747Y-138534D01*
X166965Y-140575D01*
X166747Y-142326D01*
X165874Y-144076D01*
X164563Y-145534D01*
X163035Y-146117D01*
X161289Y-145534D01*
X159760Y-143784D01*
X158887Y-141159D01*
X158669Y-138242D01*
X159105Y-134451D01*
X159760Y-132408D01*
X160852Y-130367D01*
X162380Y-128909D01*
X163909Y-128617D01*
X165437Y-129200D01*
X166529Y-130659D01*
G01X180317Y-146117D02*
X181845Y-145825D01*
X183592Y-144951D01*
X184684Y-143493D01*
X185120Y-141450D01*
X184684Y-139409D01*
X183374Y-137659D01*
X181409Y-136784D01*
X179225D01*
X177915Y-136200D01*
X176823Y-134742D01*
X176387Y-132701D01*
X177042Y-130659D01*
X178570Y-129200D01*
X180317Y-128617D01*
X182063Y-129200D01*
X183592Y-130659D01*
X184247Y-132701D01*
X183810Y-134742D01*
X182719Y-136200D01*
X181409Y-136784D01*
X179225D01*
X177260Y-137659D01*
X175950Y-139409D01*
X175514Y-141450D01*
X175950Y-143493D01*
X177042Y-144951D01*
X178789Y-145825D01*
X180317Y-146117D01*
G01X97200Y-101117D02*
Y-83617D01*
X102440D01*
X104187Y-84492D01*
X105497Y-86534D01*
X105934Y-88867D01*
X105497Y-91200D01*
X104405Y-92950D01*
X102440Y-93826D01*
X97200D01*
G01X123870Y-85076D02*
X122560Y-84200D01*
X121032Y-83617D01*
X119285D01*
X117320Y-84492D01*
X115792Y-85950D01*
X114700Y-87701D01*
X113827Y-90617D01*
X113608Y-93242D01*
X114045Y-95867D01*
X114700Y-97617D01*
X116010Y-99367D01*
X117539Y-100534D01*
X119067Y-101117D01*
X120595D01*
X122124Y-100534D01*
X123434Y-99659D01*
X124526Y-98493D01*
G01X138313Y-91784D02*
X139187Y-90909D01*
X139842Y-89451D01*
X140279Y-87408D01*
X139842Y-85659D01*
X138969Y-84492D01*
X137440Y-83617D01*
X131545D01*
Y-101117D01*
X138750D01*
X140279Y-99951D01*
X141152Y-98200D01*
X141589Y-96159D01*
X141152Y-94117D01*
X139842Y-92367D01*
X138313Y-91784D01*
X131545D01*
G01X147517Y-106950D02*
X160617D01*
G01X166545Y-101117D02*
Y-83617D01*
X176589Y-101117D01*
Y-83617D01*
G01X189067Y-101117D02*
X187320Y-100825D01*
X185792Y-99659D01*
X184482Y-97909D01*
X183608Y-95867D01*
X183172Y-93534D01*
Y-91200D01*
X183608Y-88867D01*
X184482Y-86825D01*
X185792Y-85076D01*
X187320Y-83909D01*
X189067Y-83617D01*
X190813Y-83909D01*
X192342Y-85076D01*
X193652Y-86825D01*
X194526Y-88867D01*
X194962Y-91200D01*
Y-93534D01*
X194526Y-95867D01*
X193652Y-97909D01*
X192342Y-99659D01*
X190813Y-100825D01*
X189067Y-101117D01*
G01X258282Y-143784D02*
X260029Y-145242D01*
X261994Y-146117D01*
X263740D01*
X265487Y-145242D01*
X266797Y-143784D01*
X267452Y-141742D01*
X267015Y-139701D01*
X265924Y-137950D01*
X263959Y-136784D01*
X261339Y-136200D01*
X259810Y-135034D01*
X259155Y-132992D01*
X259592Y-130950D01*
X260684Y-129492D01*
X262212Y-128617D01*
X263740D01*
X265269Y-129200D01*
X266579Y-130659D01*
G01X282113Y-136784D02*
X282987Y-135909D01*
X283642Y-134451D01*
X284079Y-132408D01*
X283642Y-130659D01*
X282769Y-129492D01*
X281240Y-128617D01*
X275345D01*
Y-146117D01*
X282550D01*
X284079Y-144951D01*
X284952Y-143200D01*
X285389Y-141159D01*
X284952Y-139117D01*
X283642Y-137367D01*
X282113Y-136784D01*
X275345D01*
G01X239908Y-83617D02*
X245367Y-101117D01*
X250826Y-83617D01*
G01X267234Y-101117D02*
X258500D01*
Y-83617D01*
X267234D01*
G01X263740Y-92075D02*
X258500D01*
G01X276000Y-101117D02*
Y-83617D01*
X281459D01*
X283205Y-84492D01*
X284297Y-85659D01*
X284734Y-87992D01*
X284297Y-90326D01*
X282987Y-91784D01*
X281459Y-92659D01*
X276000D01*
G01X281459D02*
X284734Y-101117D01*
G01X297867Y-101700D02*
X297430Y-101409D01*
Y-100825D01*
X297867Y-100534D01*
X298304Y-100825D01*
Y-101409D01*
X297867Y-101700D01*
G01X399700Y-128617D02*
Y-146117D01*
X408434D01*
G01X416764Y-142617D02*
X418073Y-144659D01*
X419820Y-145825D01*
X421785Y-146117D01*
X423532Y-145825D01*
X425279Y-144367D01*
X426370Y-142617D01*
X426589Y-140867D01*
X426152Y-138826D01*
X424624Y-137367D01*
X423095Y-136784D01*
X421130D01*
G01X423095D02*
X424405Y-135909D01*
X425497Y-134451D01*
X425934Y-132701D01*
X425497Y-130950D01*
X424405Y-129492D01*
X422440Y-128617D01*
X420475Y-128909D01*
X418510Y-130076D01*
G01X373450Y-83617D02*
Y-101117D01*
X382184D01*
G01X399247D02*
Y-89451D01*
G01Y-91492D02*
X398374Y-90326D01*
X397063Y-89742D01*
X395535Y-89451D01*
X394007Y-90034D01*
X392697Y-91200D01*
X391823Y-92950D01*
X391387Y-95284D01*
X391823Y-97617D01*
X392697Y-99367D01*
X394007Y-100534D01*
X395535Y-101117D01*
X397063Y-100825D01*
X398374Y-99951D01*
X399247Y-98784D01*
G01X408232Y-106367D02*
X409542Y-106950D01*
X411289Y-106367D01*
X412380Y-105201D01*
X413254Y-103742D01*
X414563Y-99076D01*
X417402Y-89451D01*
G01X410415D02*
X414563Y-99076D01*
G01X427042Y-93242D02*
X434029D01*
X433374Y-91200D01*
X432282Y-90034D01*
X430754Y-89451D01*
X429225Y-89742D01*
X427915Y-90617D01*
X427042Y-92659D01*
X426605Y-94409D01*
Y-96159D01*
X427042Y-97909D01*
X428134Y-99659D01*
X429444Y-100825D01*
X430972Y-101117D01*
X432500Y-100534D01*
X434029Y-98784D01*
G01X444760Y-101117D02*
Y-89451D01*
G01Y-91784D02*
X445852Y-90617D01*
X446944Y-89742D01*
X448472Y-89451D01*
X449563Y-89742D01*
X450874Y-90617D01*
G01X515564Y-101117D02*
Y-83617D01*
X519930D01*
X521677Y-84492D01*
X522987Y-85659D01*
X524079Y-87408D01*
X524952Y-89451D01*
X525170Y-92367D01*
X524952Y-95284D01*
X524079Y-97326D01*
X522987Y-99076D01*
X521677Y-100242D01*
X519930Y-101117D01*
X515564D01*
G01X534592Y-93242D02*
X541579D01*
X540924Y-91200D01*
X539832Y-90034D01*
X538304Y-89451D01*
X536775Y-89742D01*
X535465Y-90617D01*
X534592Y-92659D01*
X534155Y-94409D01*
Y-96159D01*
X534592Y-97909D01*
X535684Y-99659D01*
X536994Y-100825D01*
X538522Y-101117D01*
X540050Y-100534D01*
X541579Y-98784D01*
G01X552092Y-99076D02*
X553184Y-100242D01*
X554712Y-101117D01*
X556022D01*
X557332Y-100534D01*
X558205Y-99659D01*
X558642Y-98493D01*
X558424Y-96742D01*
X557550Y-95867D01*
X553620Y-94117D01*
X552747Y-92075D01*
X553184Y-90617D01*
X554057Y-89742D01*
X555367Y-89451D01*
X556677Y-89742D01*
X557987Y-90617D01*
G01X572867Y-89451D02*
Y-101117D01*
G01Y-84784D02*
X572430Y-84492D01*
Y-83909D01*
X572867Y-83617D01*
X573304Y-83909D01*
Y-84492D01*
X572867Y-84784D01*
G01X587310Y-105492D02*
X588839Y-106659D01*
X590585Y-106950D01*
X592113Y-106659D01*
X593424Y-105201D01*
X594297Y-103159D01*
Y-89451D01*
G01Y-91784D02*
X593424Y-90617D01*
X592113Y-89742D01*
X590585Y-89451D01*
X588839Y-90034D01*
X587747Y-91200D01*
X586873Y-93242D01*
X586437Y-95284D01*
X586655Y-97034D01*
X587529Y-99076D01*
X588839Y-100534D01*
X590585Y-101117D01*
X591895Y-100825D01*
X593424Y-99659D01*
X594297Y-98493D01*
G01X604155Y-101117D02*
Y-89451D01*
G01Y-92367D02*
X605029Y-90909D01*
X606339Y-89742D01*
X608085Y-89451D01*
X609613Y-89742D01*
X610924Y-90909D01*
X611579Y-92950D01*
Y-101117D01*
G01X622092Y-93242D02*
X629079D01*
X628424Y-91200D01*
X627332Y-90034D01*
X625804Y-89451D01*
X624275Y-89742D01*
X622965Y-90617D01*
X622092Y-92659D01*
X621655Y-94409D01*
Y-96159D01*
X622092Y-97909D01*
X623184Y-99659D01*
X624494Y-100825D01*
X626022Y-101117D01*
X627550Y-100534D01*
X629079Y-98784D01*
G01X639810Y-101117D02*
Y-89451D01*
G01Y-91784D02*
X640902Y-90617D01*
X641994Y-89742D01*
X643522Y-89451D01*
X644613Y-89742D01*
X645924Y-90617D01*
G01X559969Y-128617D02*
X568265D01*
X559969Y-146117D01*
X568265D01*
G01X581617D02*
X579870Y-145825D01*
X578342Y-144659D01*
X577032Y-142909D01*
X576158Y-140867D01*
X575722Y-138534D01*
Y-136200D01*
X576158Y-133867D01*
X577032Y-131825D01*
X578342Y-130076D01*
X579870Y-128909D01*
X581617Y-128617D01*
X583363Y-128909D01*
X584892Y-130076D01*
X586202Y-131825D01*
X587076Y-133867D01*
X587512Y-136200D01*
Y-138534D01*
X587076Y-140867D01*
X586202Y-142909D01*
X584892Y-144659D01*
X583363Y-145825D01*
X581617Y-146117D01*
G01X603484D02*
X594750D01*
Y-128617D01*
X603484D01*
G01X599990Y-137075D02*
X594750D01*
G01X686567Y-128617D02*
X684820Y-129200D01*
X683510Y-130659D01*
X682637Y-132408D01*
X681982Y-134742D01*
X681764Y-137367D01*
X681982Y-139992D01*
X682637Y-142326D01*
X683510Y-144076D01*
X684820Y-145534D01*
X686567Y-146117D01*
X688313Y-145534D01*
X689624Y-144076D01*
X690497Y-142326D01*
X691152Y-139992D01*
X691370Y-137367D01*
X691152Y-134742D01*
X690497Y-132408D01*
X689624Y-130659D01*
X688313Y-129200D01*
X686567Y-128617D01*
G01X699919Y-131534D02*
X701229Y-129784D01*
X702757Y-128909D01*
X704504Y-128617D01*
X706687Y-129200D01*
X708215Y-130659D01*
X708652Y-132408D01*
X708434Y-134159D01*
X707560Y-135617D01*
X703194Y-138534D01*
X701229Y-140575D01*
X699919Y-143493D01*
X699482Y-146117D01*
X708652D01*
G01X717637Y-146700D02*
X725497Y-128617D01*
G01X739067D02*
X737320Y-129200D01*
X736010Y-130659D01*
X735137Y-132408D01*
X734482Y-134742D01*
X734264Y-137367D01*
X734482Y-139992D01*
X735137Y-142326D01*
X736010Y-144076D01*
X737320Y-145534D01*
X739067Y-146117D01*
X740813Y-145534D01*
X742124Y-144076D01*
X742997Y-142326D01*
X743652Y-139992D01*
X743870Y-137367D01*
X743652Y-134742D01*
X742997Y-132408D01*
X742124Y-130659D01*
X740813Y-129200D01*
X739067Y-128617D01*
G01X756130Y-146117D02*
X756567Y-142326D01*
X757222Y-139117D01*
X758095Y-136200D01*
X759187Y-132992D01*
X760934Y-128617D01*
X752200D01*
G01X770137Y-146700D02*
X777997Y-128617D01*
G01X787419Y-131534D02*
X788729Y-129784D01*
X790257Y-128909D01*
X792004Y-128617D01*
X794187Y-129200D01*
X795715Y-130659D01*
X796152Y-132408D01*
X795934Y-134159D01*
X795060Y-135617D01*
X790694Y-138534D01*
X788729Y-140575D01*
X787419Y-143493D01*
X786982Y-146117D01*
X796152D01*
G01X809067Y-128617D02*
X807320Y-129200D01*
X806010Y-130659D01*
X805137Y-132408D01*
X804482Y-134742D01*
X804264Y-137367D01*
X804482Y-139992D01*
X805137Y-142326D01*
X806010Y-144076D01*
X807320Y-145534D01*
X809067Y-146117D01*
X810813Y-145534D01*
X812124Y-144076D01*
X812997Y-142326D01*
X813652Y-139992D01*
X813870Y-137367D01*
X813652Y-134742D01*
X812997Y-132408D01*
X812124Y-130659D01*
X810813Y-129200D01*
X809067Y-128617D01*
G01X826567Y-146117D02*
Y-128617D01*
X823947Y-132117D01*
G01Y-146117D02*
X829187D01*
G01X843630D02*
X844067Y-142326D01*
X844722Y-139117D01*
X845595Y-136200D01*
X846687Y-132992D01*
X848434Y-128617D01*
X839700D01*
G01X734264Y-101117D02*
Y-83617D01*
X738630D01*
X740377Y-84492D01*
X741687Y-85659D01*
X742779Y-87408D01*
X743652Y-89451D01*
X743870Y-92367D01*
X743652Y-95284D01*
X742779Y-97326D01*
X741687Y-99076D01*
X740377Y-100242D01*
X738630Y-101117D01*
X734264D01*
G01X760497D02*
Y-89451D01*
G01Y-91492D02*
X759624Y-90326D01*
X758313Y-89742D01*
X756785Y-89451D01*
X755257Y-90034D01*
X753947Y-91200D01*
X753073Y-92950D01*
X752637Y-95284D01*
X753073Y-97617D01*
X753947Y-99367D01*
X755257Y-100534D01*
X756785Y-101117D01*
X758313Y-100825D01*
X759624Y-99951D01*
X760497Y-98784D01*
G01X774067Y-83617D02*
Y-101117D01*
G01X771010Y-89451D02*
X777124D01*
G01X788292Y-93242D02*
X795279D01*
X794624Y-91200D01*
X793532Y-90034D01*
X792004Y-89451D01*
X790475Y-89742D01*
X789165Y-90617D01*
X788292Y-92659D01*
X787855Y-94409D01*
Y-96159D01*
X788292Y-97909D01*
X789384Y-99659D01*
X790694Y-100825D01*
X792222Y-101117D01*
X793750Y-100534D01*
X795279Y-98784D01*
M02*
